# S9S_MB_2U (Grand Teton) — schematic netlist excerpt (pin names and nets, part order shuffled) for the footprints in the layout excerpt that follows; sources: Cadence DE-HDL packaged netlist, KiCad conversion of 03242023_DA0F0TMBIJ0_F0T_Motherboard_J_brd_V01_OCP.brd

C844  Q_CAP_DIFFBUS  DIFF BUS_0.22UF 6.3V 20% X6S  pkg C0201  page 174 : \1\ = P5E_CPU0_PE1_TX_C_DN<12> ; \2\ = P5E_CPU0_PE1_TX_DN<12>
PC2079  Q_CAP  1UF 25V 10% X6S  pkg C0402  page 156 : A = P12V_AUX ; B = GND
R3775  Q_RES  0 5% CHIP  pkg 0402LF  page 191 : A = RST_SMB_SWITCH_N ; B = RST_SMB_E1S_N

(kicad_pcb
	(version 20260206)
	(generator "pcbnew")
	(generator_version "10.0")
	(general
		(thickness 1.6)
		(legacy_teardrops no)
	)
	(paper "A4")
	(title_block
		(title "03242023_DA0F0TMBIJ0_F0T_Motherboard_J_brd_V01_OCP.brd")
		(comment 1 "Grand Teton / footprints 2629-2631 of 6105")
	)
	(layers
		(0 "F.Cu" signal "TOP")
		(4 "In1.Cu" signal "GND")
		(6 "In2.Cu" signal "IN1")
		(8 "In3.Cu" signal "GND1")
		(10 "In4.Cu" signal "IN2")
		(12 "In5.Cu" signal "GND2")
		(14 "In6.Cu" signal "IN3")
		(16 "In7.Cu" signal "GND3")
		(18 "In8.Cu" signal "VCC")
		(20 "In9.Cu" signal "VCC1")
		(22 "In10.Cu" signal "GND4")
		(24 "In11.Cu" signal "IN4")
		(26 "In12.Cu" signal "GND5")
		(28 "In13.Cu" signal "IN5")
		(30 "In14.Cu" signal "GND6")
		(32 "In15.Cu" signal "IN6")
		(34 "In16.Cu" signal "GND7")
		(2 "B.Cu" signal "BOTTOM")
		(9 "F.Adhes" user "F.Adhesive")
		(11 "B.Adhes" user "B.Adhesive")
		(13 "F.Paste" user "Package Geometry/Pastemask Top")
		(15 "B.Paste" user "Package Geometry/Pastemask Bottom")
		(5 "F.SilkS" user "Ref Des/Silkscreen Top")
		(7 "B.SilkS" user "Ref Des/Silkscreen Bottom")
		(1 "F.Mask" user "Board Geometry/Soldermask Top")
		(3 "B.Mask" user "Board Geometry/Soldermask Bottom")
		(17 "Dwgs.User" user "User.Drawings")
		(19 "Cmts.User" user "User.Comments")
		(21 "Eco1.User" user "User.Eco1")
		(23 "Eco2.User" user "User.Eco2")
		(25 "Edge.Cuts" user "Board Geometry/Outline")
		(27 "Margin" user)
		(31 "F.CrtYd" user "Package Geometry/Place Bound Top")
		(29 "B.CrtYd" user "Package Geometry/Place Bound Bottom")
		(35 "F.Fab" user "Ref Des/Assembly Top")
		(33 "B.Fab" user "Ref Des/Assembly Bottom")
	)
	(footprint ""
		(layer "F.Cu")
		(at 398.397984 -17.612614 90)
		(property "Reference" "C844"
			(at 0 0 90)
			(layer "F.SilkS")
			(hide yes)
			(effects
				(font
					(size 1.27 1.27)
				)
			)
		)
		(property "Value" ""
			(at 0 0 90)
			(layer "F.Fab")
			(effects
				(font
					(size 1.27 1.27)
				)
			)
		)
		(duplicate_pad_numbers_are_jumpers no)
		(fp_line
			(start 0.299974 -0.150114)
			(end 0.299974 0.150114)
			(stroke
				(width 0.1)
				(type default)
			)
			(layer "F.Fab")
		)
		(fp_line
			(start -0.299974 -0.150114)
			(end 0.299974 -0.150114)
			(stroke
				(width 0.1)
				(type default)
			)
			(layer "F.Fab")
		)
		(fp_line
			(start 0.299974 0.150114)
			(end -0.299974 0.150114)
			(stroke
				(width 0.1)
				(type default)
			)
			(layer "F.Fab")
		)
		(fp_line
			(start -0.299974 0.150114)
			(end -0.299974 -0.150114)
			(stroke
				(width 0.1)
				(type default)
			)
			(layer "F.Fab")
		)
		(pad "1" smd rect
			(at -0.2667 0 90)
			(size 0.3048 0.381)
			(layers "F.Cu" "F.Mask" "F.Paste")
			(net "P5E_CPU0_PE1_TX_C_DN<12>")
		)
		(pad "2" smd rect
			(at 0.2667 0 90)
			(size 0.3048 0.381)
			(layers "F.Cu" "F.Mask" "F.Paste")
			(net "P5E_CPU0_PE1_TX_DN<12>")
		)
	)
	(footprint ""
		(layer "F.Cu")
		(at 449.044314 -25.10028 -90)
		(property "Reference" "PC2079"
			(at 0 0 270)
			(layer "F.SilkS")
			(hide yes)
			(effects
				(font
					(size 1.27 1.27)
				)
			)
		)
		(property "Value" ""
			(at 0 0 270)
			(layer "F.Fab")
			(effects
				(font
					(size 1.27 1.27)
				)
			)
		)
		(duplicate_pad_numbers_are_jumpers no)
		(fp_line
			(start -0.7874 0.4064)
			(end -0.7874 -0.4064)
			(stroke
				(width 0.1524)
				(type default)
			)
			(layer "F.SilkS")
		)
		(fp_line
			(start 0.7874 0.4064)
			(end -0.7874 0.4064)
			(stroke
				(width 0.1524)
				(type default)
			)
			(layer "F.SilkS")
		)
		(fp_line
			(start -0.7874 -0.4064)
			(end 0.7874 -0.4064)
			(stroke
				(width 0.1524)
				(type default)
			)
			(layer "F.SilkS")
		)
		(fp_line
			(start 0.7874 -0.4064)
			(end 0.7874 0.4064)
			(stroke
				(width 0.1524)
				(type default)
			)
			(layer "F.SilkS")
		)
		(fp_line
			(start -0.67945 0.3048)
			(end -0.67945 -0.305054)
			(stroke
				(width 0.1)
				(type default)
			)
			(layer "F.Fab")
		)
		(fp_line
			(start -0.12065 0.3048)
			(end -0.67945 0.3048)
			(stroke
				(width 0.1)
				(type default)
			)
			(layer "F.Fab")
		)
		(fp_line
			(start 0.120396 0.3048)
			(end 0.120396 0.2794)
			(stroke
				(width 0.1)
				(type default)
			)
			(layer "F.Fab")
		)
		(fp_line
			(start 0.67945 0.3048)
			(end 0.120396 0.3048)
			(stroke
				(width 0.1)
				(type default)
			)
			(layer "F.Fab")
		)
		(fp_line
			(start -0.12065 0.2794)
			(end -0.12065 0.3048)
			(stroke
				(width 0.1)
				(type default)
			)
			(layer "F.Fab")
		)
		(fp_line
			(start 0.120396 0.2794)
			(end -0.12065 0.2794)
			(stroke
				(width 0.1)
				(type default)
			)
			(layer "F.Fab")
		)
		(fp_line
			(start -0.12065 -0.2794)
			(end 0.12065 -0.2794)
			(stroke
				(width 0.1)
				(type default)
			)
			(layer "F.Fab")
		)
		(fp_line
			(start 0.12065 -0.2794)
			(end 0.12065 -0.3048)
			(stroke
				(width 0.1)
				(type default)
			)
			(layer "F.Fab")
		)
		(fp_line
			(start 0.12065 -0.3048)
			(end 0.67945 -0.3048)
			(stroke
				(width 0.1)
				(type default)
			)
			(layer "F.Fab")
		)
		(fp_line
			(start 0.67945 -0.3048)
			(end 0.67945 0.3048)
			(stroke
				(width 0.1)
				(type default)
			)
			(layer "F.Fab")
		)
		(fp_line
			(start -0.67945 -0.305054)
			(end -0.12065 -0.305054)
			(stroke
				(width 0.1)
				(type default)
			)
			(layer "F.Fab")
		)
		(fp_line
			(start -0.12065 -0.305054)
			(end -0.12065 -0.2794)
			(stroke
				(width 0.1)
				(type default)
			)
			(layer "F.Fab")
		)
		(pad "1" smd circle
			(at -0.40005 0 270)
			(size 0 0)
			(layers "F.Cu" "F.Mask" "F.Paste")
			(net "P12V_AUX")
		)
		(pad "2" smd circle
			(at 0.40005 0 270)
			(size 0 0)
			(layers "F.Cu" "F.Mask" "F.Paste")
			(net "GND")
		)
	)
	(footprint ""
		(layer "F.Cu")
		(at 151.844756 -65.413128)
		(property "Reference" "R3775"
			(at 0 0 0)
			(layer "F.SilkS")
			(hide yes)
			(effects
				(font
					(size 1.27 1.27)
				)
			)
		)
		(property "Value" ""
			(at 0 0 0)
			(layer "F.Fab")
			(effects
				(font
					(size 1.27 1.27)
				)
			)
		)
		(duplicate_pad_numbers_are_jumpers no)
		(fp_line
			(start -0.7874 -0.4064)
			(end 0.7874 -0.4064)
			(stroke
				(width 0.1524)
				(type default)
			)
			(layer "F.SilkS")
		)
		(fp_line
			(start -0.7874 0.4064)
			(end -0.7874 -0.4064)
			(stroke
				(width 0.1524)
				(type default)
			)
			(layer "F.SilkS")
		)
		(fp_line
			(start 0.7874 -0.4064)
			(end 0.7874 0.4064)
			(stroke
				(width 0.1524)
				(type default)
			)
			(layer "F.SilkS")
		)
		(fp_line
			(start 0.7874 0.4064)
			(end -0.7874 0.4064)
			(stroke
				(width 0.1524)
				(type default)
			)
			(layer "F.SilkS")
		)
		(fp_line
			(start -0.67945 -0.305054)
			(end -0.12065 -0.305054)
			(stroke
				(width 0.1)
				(type default)
			)
			(layer "F.Fab")
		)
		(fp_line
			(start -0.67945 0.3048)
			(end -0.67945 -0.305054)
			(stroke
				(width 0.1)
				(type default)
			)
			(layer "F.Fab")
		)
		(fp_line
			(start -0.12065 -0.305054)
			(end -0.12065 -0.2794)
			(stroke
				(width 0.1)
				(type default)
			)
			(layer "F.Fab")
		)
		(fp_line
			(start -0.12065 -0.2794)
			(end 0.12065 -0.2794)
			(stroke
				(width 0.1)
				(type default)
			)
			(layer "F.Fab")
		)
		(fp_line
			(start -0.12065 0.2794)
			(end -0.12065 0.3048)
			(stroke
				(width 0.1)
				(type default)
			)
			(layer "F.Fab")
		)
		(fp_line
			(start -0.12065 0.3048)
			(end -0.67945 0.3048)
			(stroke
				(width 0.1)
				(type default)
			)
			(layer "F.Fab")
		)
		(fp_line
			(start 0.120396 0.2794)
			(end -0.12065 0.2794)
			(stroke
				(width 0.1)
				(type default)
			)
			(layer "F.Fab")
		)
		(fp_line
			(start 0.120396 0.3048)
			(end 0.120396 0.2794)
			(stroke
				(width 0.1)
				(type default)
			)
			(layer "F.Fab")
		)
		(fp_line
			(start 0.12065 -0.3048)
			(end 0.67945 -0.3048)
			(stroke
				(width 0.1)
				(type default)
			)
			(layer "F.Fab")
		)
		(fp_line
			(start 0.12065 -0.2794)
			(end 0.12065 -0.3048)
			(stroke
				(width 0.1)
				(type default)
			)
			(layer "F.Fab")
		)
		(fp_line
			(start 0.67945 -0.3048)
			(end 0.67945 0.3048)
			(stroke
				(width 0.1)
				(type default)
			)
			(layer "F.Fab")
		)
		(fp_line
			(start 0.67945 0.3048)
			(end 0.120396 0.3048)
			(stroke
				(width 0.1)
				(type default)
			)
			(layer "F.Fab")
		)
		(pad "1" smd circle
			(at -0.40005 0)
			(size 0 0)
			(layers "F.Cu" "F.Mask" "F.Paste")
			(net "RST_SMB_SWITCH_N")
		)
		(pad "2" smd circle
			(at 0.40005 0)
			(size 0 0)
			(layers "F.Cu" "F.Mask" "F.Paste")
			(net "RST_SMB_E1S_N")
		)
	)
)
